(kicad_pcb
	(version 20260206)
	(generator "pcbnew")
	(generator_version "10.0")
	(general
		(thickness 1.6)
		(legacy_teardrops no)
	)
	(paper "A4")
	(title_block
		(title "01162023_DA0F0TEBIF0_F0T_Expander_BD_F_brd_V02_OCP.brd")
		(comment 1 "Grand Teton / footprints 4301-4305 of 9728")
	)
	(layers
		(0 "F.Cu" signal "TOP")
		(4 "In1.Cu" signal "GND")
		(6 "In2.Cu" signal "VCC")
		(8 "In3.Cu" signal "VCC1")
		(10 "In4.Cu" signal "GND1")
		(12 "In5.Cu" signal "IN1")
		(14 "In6.Cu" signal "GND2")
		(16 "In7.Cu" signal "IN2")
		(18 "In8.Cu" signal "GND3")
		(20 "In9.Cu" signal "IN3")
		(22 "In10.Cu" signal "GND4")
		(24 "In11.Cu" signal "IN4")
		(26 "In12.Cu" signal "GND5")
		(28 "In13.Cu" signal "IN5")
		(30 "In14.Cu" signal "GND6")
		(32 "In15.Cu" signal "IN6")
		(34 "In16.Cu" signal "GND7")
		(2 "B.Cu" signal "BOTTOM")
		(9 "F.Adhes" user "F.Adhesive")
		(11 "B.Adhes" user "B.Adhesive")
		(13 "F.Paste" user "Package Geometry/Pastemask Top")
		(15 "B.Paste" user "Package Geometry/Pastemask Bottom")
		(5 "F.SilkS" user "Ref Des/Silkscreen Top")
		(7 "B.SilkS" user "Ref Des/Silkscreen Bottom")
		(1 "F.Mask" user "Board Geometry/Soldermask Top")
		(3 "B.Mask" user "Board Geometry/Soldermask Bottom")
		(17 "Dwgs.User" user "User.Drawings")
		(19 "Cmts.User" user "User.Comments")
		(21 "Eco1.User" user "User.Eco1")
		(23 "Eco2.User" user "User.Eco2")
		(25 "Edge.Cuts" user "Board Geometry/Outline")
		(27 "Margin" user)
		(31 "F.CrtYd" user "Package Geometry/Place Bound Top")
		(29 "B.CrtYd" user "Package Geometry/Place Bound Bottom")
		(35 "F.Fab" user "Ref Des/Assembly Top")
		(33 "B.Fab" user "Ref Des/Assembly Bottom")
	)
	(footprint ""
		(layer "F.Cu")
		(at 5.656326 -61.487812 180)
		(property "Reference" "R5836"
			(at 0 0 180)
			(layer "F.SilkS")
			(hide yes)
			(effects
				(font
					(size 1.27 1.27)
				)
			)
		)
		(property "Value" ""
			(at 0 0 180)
			(layer "F.Fab")
			(effects
				(font
					(size 1.27 1.27)
				)
			)
		)
		(duplicate_pad_numbers_are_jumpers no)
		(fp_line
			(start 0.7874 0.4064)
			(end -0.7874 0.4064)
			(stroke
				(width 0.1524)
				(type default)
			)
			(layer "F.SilkS")
		)
		(fp_line
			(start 0.7874 -0.4064)
			(end 0.7874 0.4064)
			(stroke
				(width 0.1524)
				(type default)
			)
			(layer "F.SilkS")
		)
		(fp_line
			(start -0.7874 0.4064)
			(end -0.7874 -0.4064)
			(stroke
				(width 0.1524)
				(type default)
			)
			(layer "F.SilkS")
		)
		(fp_line
			(start -0.7874 -0.4064)
			(end 0.7874 -0.4064)
			(stroke
				(width 0.1524)
				(type default)
			)
			(layer "F.SilkS")
		)
		(fp_line
			(start 0.67945 0.3048)
			(end 0.120396 0.3048)
			(stroke
				(width 0.1)
				(type default)
			)
			(layer "F.Fab")
		)
		(fp_line
			(start 0.67945 -0.3048)
			(end 0.67945 0.3048)
			(stroke
				(width 0.1)
				(type default)
			)
			(layer "F.Fab")
		)
		(fp_line
			(start 0.12065 -0.2794)
			(end 0.12065 -0.3048)
			(stroke
				(width 0.1)
				(type default)
			)
			(layer "F.Fab")
		)
		(fp_line
			(start 0.12065 -0.3048)
			(end 0.67945 -0.3048)
			(stroke
				(width 0.1)
				(type default)
			)
			(layer "F.Fab")
		)
		(fp_line
			(start 0.120396 0.3048)
			(end 0.120396 0.2794)
			(stroke
				(width 0.1)
				(type default)
			)
			(layer "F.Fab")
		)
		(fp_line
			(start 0.120396 0.2794)
			(end -0.12065 0.2794)
			(stroke
				(width 0.1)
				(type default)
			)
			(layer "F.Fab")
		)
		(fp_line
			(start -0.12065 0.3048)
			(end -0.67945 0.3048)
			(stroke
				(width 0.1)
				(type default)
			)
			(layer "F.Fab")
		)
		(fp_line
			(start -0.12065 0.2794)
			(end -0.12065 0.3048)
			(stroke
				(width 0.1)
				(type default)
			)
			(layer "F.Fab")
		)
		(fp_line
			(start -0.12065 -0.2794)
			(end 0.12065 -0.2794)
			(stroke
				(width 0.1)
				(type default)
			)
			(layer "F.Fab")
		)
		(fp_line
			(start -0.12065 -0.305054)
			(end -0.12065 -0.2794)
			(stroke
				(width 0.1)
				(type default)
			)
			(layer "F.Fab")
		)
		(fp_line
			(start -0.67945 0.3048)
			(end -0.67945 -0.305054)
			(stroke
				(width 0.1)
				(type default)
			)
			(layer "F.Fab")
		)
		(fp_line
			(start -0.67945 -0.305054)
			(end -0.12065 -0.305054)
			(stroke
				(width 0.1)
				(type default)
			)
			(layer "F.Fab")
		)
		(pad "1" smd circle
			(at -0.40005 0 180)
			(size 0 0)
			(layers "F.Cu" "F.Mask" "F.Paste")
			(net "P3V3_AUX")
		)
		(pad "2" smd circle
			(at 0.40005 0 180)
			(size 0 0)
			(layers "F.Cu" "F.Mask" "F.Paste")
			(net "PWRGD_P12V_SSD0_D")
		)
	)
	(footprint ""
		(layer "F.Cu")
		(at 63.47079 -137.848848 180)
		(property "Reference" "R57"
			(at 0 0 180)
			(layer "F.SilkS")
			(hide yes)
			(effects
				(font
					(size 1.27 1.27)
				)
			)
		)
		(property "Value" ""
			(at 0 0 180)
			(layer "F.Fab")
			(effects
				(font
					(size 1.27 1.27)
				)
			)
		)
		(duplicate_pad_numbers_are_jumpers no)
		(fp_line
			(start 0.7874 0.4064)
			(end -0.7874 0.4064)
			(stroke
				(width 0.1524)
				(type default)
			)
			(layer "F.SilkS")
		)
		(fp_line
			(start 0.7874 -0.4064)
			(end 0.7874 0.4064)
			(stroke
				(width 0.1524)
				(type default)
			)
			(layer "F.SilkS")
		)
		(fp_line
			(start -0.7874 0.4064)
			(end -0.7874 -0.4064)
			(stroke
				(width 0.1524)
				(type default)
			)
			(layer "F.SilkS")
		)
		(fp_line
			(start -0.7874 -0.4064)
			(end 0.7874 -0.4064)
			(stroke
				(width 0.1524)
				(type default)
			)
			(layer "F.SilkS")
		)
		(fp_line
			(start 0.67945 0.3048)
			(end 0.120396 0.3048)
			(stroke
				(width 0.1)
				(type default)
			)
			(layer "F.Fab")
		)
		(fp_line
			(start 0.67945 -0.3048)
			(end 0.67945 0.3048)
			(stroke
				(width 0.1)
				(type default)
			)
			(layer "F.Fab")
		)
		(fp_line
			(start 0.12065 -0.2794)
			(end 0.12065 -0.3048)
			(stroke
				(width 0.1)
				(type default)
			)
			(layer "F.Fab")
		)
		(fp_line
			(start 0.12065 -0.3048)
			(end 0.67945 -0.3048)
			(stroke
				(width 0.1)
				(type default)
			)
			(layer "F.Fab")
		)
		(fp_line
			(start 0.120396 0.3048)
			(end 0.120396 0.2794)
			(stroke
				(width 0.1)
				(type default)
			)
			(layer "F.Fab")
		)
		(fp_line
			(start 0.120396 0.2794)
			(end -0.12065 0.2794)
			(stroke
				(width 0.1)
				(type default)
			)
			(layer "F.Fab")
		)
		(fp_line
			(start -0.12065 0.3048)
			(end -0.67945 0.3048)
			(stroke
				(width 0.1)
				(type default)
			)
			(layer "F.Fab")
		)
		(fp_line
			(start -0.12065 0.2794)
			(end -0.12065 0.3048)
			(stroke
				(width 0.1)
				(type default)
			)
			(layer "F.Fab")
		)
		(fp_line
			(start -0.12065 -0.2794)
			(end 0.12065 -0.2794)
			(stroke
				(width 0.1)
				(type default)
			)
			(layer "F.Fab")
		)
		(fp_line
			(start -0.12065 -0.305054)
			(end -0.12065 -0.2794)
			(stroke
				(width 0.1)
				(type default)
			)
			(layer "F.Fab")
		)
		(fp_line
			(start -0.67945 0.3048)
			(end -0.67945 -0.305054)
			(stroke
				(width 0.1)
				(type default)
			)
			(layer "F.Fab")
		)
		(fp_line
			(start -0.67945 -0.305054)
			(end -0.12065 -0.305054)
			(stroke
				(width 0.1)
				(type default)
			)
			(layer "F.Fab")
		)
		(pad "1" smd circle
			(at -0.40005 0 180)
			(size 0 0)
			(layers "F.Cu" "F.Mask" "F.Paste")
			(net "PRSNTB1_NIC1_N")
		)
		(pad "2" smd circle
			(at 0.40005 0 180)
			(size 0 0)
			(layers "F.Cu" "F.Mask" "F.Paste")
			(net "P3V3_AUX")
		)
	)
	(footprint ""
		(layer "F.Cu")
		(at 105.7148 -202.4634 -90)
		(property "Reference" "R6631"
			(at 0 0 270)
			(layer "F.SilkS")
			(hide yes)
			(effects
				(font
					(size 1.27 1.27)
				)
			)
		)
		(property "Value" ""
			(at 0 0 270)
			(layer "F.Fab")
			(effects
				(font
					(size 1.27 1.27)
				)
			)
		)
		(duplicate_pad_numbers_are_jumpers no)
		(fp_line
			(start -0.7874 0.4064)
			(end -0.7874 -0.4064)
			(stroke
				(width 0.1524)
				(type default)
			)
			(layer "F.SilkS")
		)
		(fp_line
			(start 0.7874 0.4064)
			(end -0.7874 0.4064)
			(stroke
				(width 0.1524)
				(type default)
			)
			(layer "F.SilkS")
		)
		(fp_line
			(start -0.7874 -0.4064)
			(end 0.7874 -0.4064)
			(stroke
				(width 0.1524)
				(type default)
			)
			(layer "F.SilkS")
		)
		(fp_line
			(start 0.7874 -0.4064)
			(end 0.7874 0.4064)
			(stroke
				(width 0.1524)
				(type default)
			)
			(layer "F.SilkS")
		)
		(fp_line
			(start -0.67945 0.3048)
			(end -0.67945 -0.305054)
			(stroke
				(width 0.1)
				(type default)
			)
			(layer "F.Fab")
		)
		(fp_line
			(start -0.12065 0.3048)
			(end -0.67945 0.3048)
			(stroke
				(width 0.1)
				(type default)
			)
			(layer "F.Fab")
		)
		(fp_line
			(start 0.120396 0.3048)
			(end 0.120396 0.2794)
			(stroke
				(width 0.1)
				(type default)
			)
			(layer "F.Fab")
		)
		(fp_line
			(start 0.67945 0.3048)
			(end 0.120396 0.3048)
			(stroke
				(width 0.1)
				(type default)
			)
			(layer "F.Fab")
		)
		(fp_line
			(start -0.12065 0.2794)
			(end -0.12065 0.3048)
			(stroke
				(width 0.1)
				(type default)
			)
			(layer "F.Fab")
		)
		(fp_line
			(start 0.120396 0.2794)
			(end -0.12065 0.2794)
			(stroke
				(width 0.1)
				(type default)
			)
			(layer "F.Fab")
		)
		(fp_line
			(start -0.12065 -0.2794)
			(end 0.12065 -0.2794)
			(stroke
				(width 0.1)
				(type default)
			)
			(layer "F.Fab")
		)
		(fp_line
			(start 0.12065 -0.2794)
			(end 0.12065 -0.3048)
			(stroke
				(width 0.1)
				(type default)
			)
			(layer "F.Fab")
		)
		(fp_line
			(start 0.12065 -0.3048)
			(end 0.67945 -0.3048)
			(stroke
				(width 0.1)
				(type default)
			)
			(layer "F.Fab")
		)
		(fp_line
			(start 0.67945 -0.3048)
			(end 0.67945 0.3048)
			(stroke
				(width 0.1)
				(type default)
			)
			(layer "F.Fab")
		)
		(fp_line
			(start -0.67945 -0.305054)
			(end -0.12065 -0.305054)
			(stroke
				(width 0.1)
				(type default)
			)
			(layer "F.Fab")
		)
		(fp_line
			(start -0.12065 -0.305054)
			(end -0.12065 -0.2794)
			(stroke
				(width 0.1)
				(type default)
			)
			(layer "F.Fab")
		)
		(pad "1" smd circle
			(at -0.40005 0 270)
			(size 0 0)
			(layers "F.Cu" "F.Mask" "F.Paste")
			(net "UART_PEX0_CLI_BUF_R_TX")
		)
		(pad "2" smd circle
			(at 0.40005 0 270)
			(size 0 0)
			(layers "F.Cu" "F.Mask" "F.Paste")
			(net "UART_PEX0_CLI_CP2108_TX")
		)
	)
	(footprint ""
		(layer "F.Cu")
		(at 382.479042 -59.577986 -90)
		(property "Reference" "R897"
			(at 0 0 270)
			(layer "F.SilkS")
			(hide yes)
			(effects
				(font
					(size 1.27 1.27)
				)
			)
		)
		(property "Value" ""
			(at 0 0 270)
			(layer "F.Fab")
			(effects
				(font
					(size 1.27 1.27)
				)
			)
		)
		(duplicate_pad_numbers_are_jumpers no)
		(fp_line
			(start -0.7874 0.4064)
			(end -0.7874 -0.4064)
			(stroke
				(width 0.1524)
				(type default)
			)
			(layer "F.SilkS")
		)
		(fp_line
			(start 0.7874 0.4064)
			(end -0.7874 0.4064)
			(stroke
				(width 0.1524)
				(type default)
			)
			(layer "F.SilkS")
		)
		(fp_line
			(start -0.7874 -0.4064)
			(end 0.7874 -0.4064)
			(stroke
				(width 0.1524)
				(type default)
			)
			(layer "F.SilkS")
		)
		(fp_line
			(start 0.7874 -0.4064)
			(end 0.7874 0.4064)
			(stroke
				(width 0.1524)
				(type default)
			)
			(layer "F.SilkS")
		)
		(fp_line
			(start -0.67945 0.3048)
			(end -0.67945 -0.305054)
			(stroke
				(width 0.1)
				(type default)
			)
			(layer "F.Fab")
		)
		(fp_line
			(start -0.12065 0.3048)
			(end -0.67945 0.3048)
			(stroke
				(width 0.1)
				(type default)
			)
			(layer "F.Fab")
		)
		(fp_line
			(start 0.120396 0.3048)
			(end 0.120396 0.2794)
			(stroke
				(width 0.1)
				(type default)
			)
			(layer "F.Fab")
		)
		(fp_line
			(start 0.67945 0.3048)
			(end 0.120396 0.3048)
			(stroke
				(width 0.1)
				(type default)
			)
			(layer "F.Fab")
		)
		(fp_line
			(start -0.12065 0.2794)
			(end -0.12065 0.3048)
			(stroke
				(width 0.1)
				(type default)
			)
			(layer "F.Fab")
		)
		(fp_line
			(start 0.120396 0.2794)
			(end -0.12065 0.2794)
			(stroke
				(width 0.1)
				(type default)
			)
			(layer "F.Fab")
		)
		(fp_line
			(start -0.12065 -0.2794)
			(end 0.12065 -0.2794)
			(stroke
				(width 0.1)
				(type default)
			)
			(layer "F.Fab")
		)
		(fp_line
			(start 0.12065 -0.2794)
			(end 0.12065 -0.3048)
			(stroke
				(width 0.1)
				(type default)
			)
			(layer "F.Fab")
		)
		(fp_line
			(start 0.12065 -0.3048)
			(end 0.67945 -0.3048)
			(stroke
				(width 0.1)
				(type default)
			)
			(layer "F.Fab")
		)
		(fp_line
			(start 0.67945 -0.3048)
			(end 0.67945 0.3048)
			(stroke
				(width 0.1)
				(type default)
			)
			(layer "F.Fab")
		)
		(fp_line
			(start -0.67945 -0.305054)
			(end -0.12065 -0.305054)
			(stroke
				(width 0.1)
				(type default)
			)
			(layer "F.Fab")
		)
		(fp_line
			(start -0.12065 -0.305054)
			(end -0.12065 -0.2794)
			(stroke
				(width 0.1)
				(type default)
			)
			(layer "F.Fab")
		)
		(pad "1" smd circle
			(at -0.40005 0 270)
			(size 0 0)
			(layers "F.Cu" "F.Mask" "F.Paste")
			(net "P3V3_SSD13")
		)
		(pad "2" smd circle
			(at 0.40005 0 270)
			(size 0 0)
			(layers "F.Cu" "F.Mask" "F.Paste")
			(net "PWRGD_P3V3_SSD13")
		)
	)
	(footprint ""
		(layer "F.Cu")
		(at 358.013 -224.536 180)
		(property "Reference" "R3624"
			(at 0 0 180)
			(layer "F.SilkS")
			(hide yes)
			(effects
				(font
					(size 1.27 1.27)
				)
			)
		)
		(property "Value" ""
			(at 0 0 180)
			(layer "F.Fab")
			(effects
				(font
					(size 1.27 1.27)
				)
			)
		)
		(duplicate_pad_numbers_are_jumpers no)
		(fp_line
			(start 0.7874 0.4064)
			(end -0.7874 0.4064)
			(stroke
				(width 0.1524)
				(type default)
			)
			(layer "F.SilkS")
		)
		(fp_line
			(start 0.7874 -0.4064)
			(end 0.7874 0.4064)
			(stroke
				(width 0.1524)
				(type default)
			)
			(layer "F.SilkS")
		)
		(fp_line
			(start -0.7874 0.4064)
			(end -0.7874 -0.4064)
			(stroke
				(width 0.1524)
				(type default)
			)
			(layer "F.SilkS")
		)
		(fp_line
			(start -0.7874 -0.4064)
			(end 0.7874 -0.4064)
			(stroke
				(width 0.1524)
				(type default)
			)
			(layer "F.SilkS")
		)
		(fp_line
			(start 0.67945 0.3048)
			(end 0.120396 0.3048)
			(stroke
				(width 0.1)
				(type default)
			)
			(layer "F.Fab")
		)
		(fp_line
			(start 0.67945 -0.3048)
			(end 0.67945 0.3048)
			(stroke
				(width 0.1)
				(type default)
			)
			(layer "F.Fab")
		)
		(fp_line
			(start 0.12065 -0.2794)
			(end 0.12065 -0.3048)
			(stroke
				(width 0.1)
				(type default)
			)
			(layer "F.Fab")
		)
		(fp_line
			(start 0.12065 -0.3048)
			(end 0.67945 -0.3048)
			(stroke
				(width 0.1)
				(type default)
			)
			(layer "F.Fab")
		)
		(fp_line
			(start 0.120396 0.3048)
			(end 0.120396 0.2794)
			(stroke
				(width 0.1)
				(type default)
			)
			(layer "F.Fab")
		)
		(fp_line
			(start 0.120396 0.2794)
			(end -0.12065 0.2794)
			(stroke
				(width 0.1)
				(type default)
			)
			(layer "F.Fab")
		)
		(fp_line
			(start -0.12065 0.3048)
			(end -0.67945 0.3048)
			(stroke
				(width 0.1)
				(type default)
			)
			(layer "F.Fab")
		)
		(fp_line
			(start -0.12065 0.2794)
			(end -0.12065 0.3048)
			(stroke
				(width 0.1)
				(type default)
			)
			(layer "F.Fab")
		)
		(fp_line
			(start -0.12065 -0.2794)
			(end 0.12065 -0.2794)
			(stroke
				(width 0.1)
				(type default)
			)
			(layer "F.Fab")
		)
		(fp_line
			(start -0.12065 -0.305054)
			(end -0.12065 -0.2794)
			(stroke
				(width 0.1)
				(type default)
			)
			(layer "F.Fab")
		)
		(fp_line
			(start -0.67945 0.3048)
			(end -0.67945 -0.305054)
			(stroke
				(width 0.1)
				(type default)
			)
			(layer "F.Fab")
		)
		(fp_line
			(start -0.67945 -0.305054)
			(end -0.12065 -0.305054)
			(stroke
				(width 0.1)
				(type default)
			)
			(layer "F.Fab")
		)
		(pad "1" smd circle
			(at -0.40005 0 180)
			(size 0 0)
			(layers "F.Cu" "F.Mask" "F.Paste")
			(net "NIC2_CLK_EN_R_N")
		)
		(pad "2" smd circle
			(at 0.40005 0 180)
			(size 0 0)
			(layers "F.Cu" "F.Mask" "F.Paste")
			(net "NIC2_CLK_EN_N")
		)
	)
)
